(kicad_pcb
	(version 20260206)
	(generator "pcbnew")
	(generator_version "10.0")
	(general
		(thickness 1.6)
		(legacy_teardrops no)
	)
	(paper "A4")
	(title_block
		(title "04192023_DAF0TMB3IC0_F0TG_MB_C_brd_V02_OCP.brd")
		(comment 1 "Grand Teton / footprint 3975 of 8354 (U6014), pads 1-111 of 354")
	)
	(layers
		(0 "F.Cu" signal "TOP")
		(4 "In1.Cu" signal "GND")
		(6 "In2.Cu" signal "IN1")
		(8 "In3.Cu" signal "GND1")
		(10 "In4.Cu" signal "IN2")
		(12 "In5.Cu" signal "GND2")
		(14 "In6.Cu" signal "IN3")
		(16 "In7.Cu" signal "GND3")
		(18 "In8.Cu" signal "VCC")
		(20 "In9.Cu" signal "VCC1")
		(22 "In10.Cu" signal "GND4")
		(24 "In11.Cu" signal "IN4")
		(26 "In12.Cu" signal "GND5")
		(28 "In13.Cu" signal "IN5")
		(30 "In14.Cu" signal "GND6")
		(32 "In15.Cu" signal "IN6")
		(34 "In16.Cu" signal "GND7")
		(2 "B.Cu" signal "BOTTOM")
		(9 "F.Adhes" user "F.Adhesive")
		(11 "B.Adhes" user "B.Adhesive")
		(13 "F.Paste" user "Package Geometry/Pastemask Top")
		(15 "B.Paste" user "Package Geometry/Pastemask Bottom")
		(5 "F.SilkS" user "Ref Des/Silkscreen Top")
		(7 "B.SilkS" user "Ref Des/Silkscreen Bottom")
		(1 "F.Mask" user "Board Geometry/Soldermask Top")
		(3 "B.Mask" user "Board Geometry/Soldermask Bottom")
		(17 "Dwgs.User" user "User.Drawings")
		(19 "Cmts.User" user "User.Comments")
		(21 "Eco1.User" user "User.Eco1")
		(23 "Eco2.User" user "User.Eco2")
		(25 "Edge.Cuts" user "Board Geometry/Outline")
		(27 "Margin" user)
		(31 "F.CrtYd" user "Package Geometry/Place Bound Top")
		(29 "B.CrtYd" user "Package Geometry/Place Bound Bottom")
		(35 "F.Fab" user "Ref Des/Assembly Top")
		(33 "B.Fab" user "Ref Des/Assembly Bottom")
	)
	(footprint ""
		(layer "F.Cu")
		(at 56.46801 -387.342634)
		(property "Reference" "U6014"
			(at -6.735064 -7.919974 0)
			(unlocked yes)
			(layer "F.SilkS")
			(effects
				(font
					(size 0.7874 0.5842)
					(thickness 0.1524)
				)
				(justify left)
			)
		)
		(property "Value" ""
			(at 0 0 0)
			(layer "F.Fab")
			(effects
				(font
					(size 1.27 1.27)
				)
			)
		)
		(duplicate_pad_numbers_are_jumpers no)
		(pad "A1" smd oval
			(at 11.050016 -3.938524)
			(size 0.254 0.3302)
			(layers "F.Cu" "F.Mask" "F.Paste")
			(net "NCF_A1_CPU1_P0_GND")
		)
		(pad "A35" smd oval
			(at 11.050016 3.940048)
			(size 0.254 0.3302)
			(layers "F.Cu" "F.Mask" "F.Paste")
			(net "NCF_CPU1_P0_GND")
		)
		(pad "AA10" smd circle
			(at 7.602728 -1.431798)
			(size 0.381 0.381)
			(layers "F.Cu" "F.Mask" "F.Paste")
			(net "P5E_CPU1_P0_TX_BUF_DN<14>")
		)
		(pad "AA29" smd circle
			(at 7.602728 2.032254)
			(size 0.381 0.381)
			(layers "F.Cu" "F.Mask" "F.Paste")
			(net "P5E_CPU1_P0_RX_DN<14>")
		)
		(pad "AB1" smd oval
			(at 7.450074 -3.938524)
			(size 0.254 0.3302)
			(layers "F.Cu" "F.Mask" "F.Paste")
			(net "P5E_CPU1_P0_RX_BUF_DP<14>")
		)
		(pad "AB35" smd oval
			(at 7.450074 3.940048)
			(size 0.254 0.3302)
			(layers "F.Cu" "F.Mask" "F.Paste")
			(net "P5E_CPU1_P0_TX_C_DP<14>")
		)
		(pad "AC4" smd circle
			(at 7.202678 -2.817368)
			(size 0.381 0.381)
			(layers "F.Cu" "F.Mask" "F.Paste")
			(net "GND")
		)
		(pad "AC13" smd circle
			(at 7.202678 -0.79629)
			(size 0.3048 0.3048)
			(layers "F.Cu" "F.Mask" "F.Paste")
			(net "GND")
		)
		(pad "AC17" smd circle
			(at 7.202678 -0.296164)
			(size 0.3048 0.3048)
			(layers "F.Cu" "F.Mask" "F.Paste")
			(net "P0V9_CPU1_RT0_2A")
		)
		(pad "AC20" smd circle
			(at 7.202678 0.203708)
			(size 0.3048 0.3048)
			(layers "F.Cu" "F.Mask" "F.Paste")
			(net "P0V9_CPU1_RT0_2A")
		)
		(pad "AC22" smd circle
			(at 7.202678 0.703834)
			(size 0.3048 0.3048)
			(layers "F.Cu" "F.Mask" "F.Paste")
			(net "GND")
		)
		(pad "AC32" smd circle
			(at 7.202678 2.724912)
			(size 0.381 0.381)
			(layers "F.Cu" "F.Mask" "F.Paste")
			(net "GND")
		)
		(pad "AD2" smd circle
			(at 7.1501 -3.41884)
			(size 0.3048 0.3048)
			(layers "F.Cu" "F.Mask" "F.Paste")
			(net "GND")
		)
		(pad "AD34" smd circle
			(at 7.1501 3.420364)
			(size 0.3048 0.3048)
			(layers "F.Cu" "F.Mask" "F.Paste")
			(net "GND")
		)
		(pad "AE1" smd oval
			(at 6.849872 -3.938524)
			(size 0.254 0.3302)
			(layers "F.Cu" "F.Mask" "F.Paste")
			(net "GND")
		)
		(pad "AE35" smd oval
			(at 6.849872 3.940048)
			(size 0.254 0.3302)
			(layers "F.Cu" "F.Mask" "F.Paste")
			(net "GND")
		)
		(pad "AF7" smd circle
			(at 6.802628 -2.12471)
			(size 0.381 0.381)
			(layers "F.Cu" "F.Mask" "F.Paste")
			(net "P5E_CPU1_P0_TX_BUF_DP<13>")
		)
		(pad "AF26" smd circle
			(at 6.802628 1.339342)
			(size 0.381 0.381)
			(layers "F.Cu" "F.Mask" "F.Paste")
			(net "P5E_CPU1_P0_RX_DP<13>")
		)
		(pad "AG2" smd circle
			(at 6.549898 -3.41884)
			(size 0.3048 0.3048)
			(layers "F.Cu" "F.Mask" "F.Paste")
			(net "P5E_CPU1_P0_RX_BUF_DN<13>")
		)
		(pad "AG34" smd circle
			(at 6.549898 3.420364)
			(size 0.3048 0.3048)
			(layers "F.Cu" "F.Mask" "F.Paste")
			(net "P5E_CPU1_P0_TX_C_DP<13>")
		)
		(pad "AH10" smd circle
			(at 6.402578 -1.431798)
			(size 0.381 0.381)
			(layers "F.Cu" "F.Mask" "F.Paste")
			(net "P5E_CPU1_P0_TX_BUF_DN<13>")
		)
		(pad "AH29" smd circle
			(at 6.402578 2.032254)
			(size 0.381 0.381)
			(layers "F.Cu" "F.Mask" "F.Paste")
			(net "P5E_CPU1_P0_RX_DN<13>")
		)
		(pad "AJ1" smd oval
			(at 6.249924 -3.938524)
			(size 0.254 0.3302)
			(layers "F.Cu" "F.Mask" "F.Paste")
			(net "P5E_CPU1_P0_RX_BUF_DP<13>")
		)
		(pad "AJ35" smd oval
			(at 6.249924 3.940048)
			(size 0.254 0.3302)
			(layers "F.Cu" "F.Mask" "F.Paste")
			(net "P5E_CPU1_P0_TX_C_DN<13>")
		)
		(pad "AK4" smd circle
			(at 6.002528 -2.817368)
			(size 0.381 0.381)
			(layers "F.Cu" "F.Mask" "F.Paste")
			(net "GND")
		)
		(pad "AK13" smd circle
			(at 6.002528 -0.79629)
			(size 0.3048 0.3048)
			(layers "F.Cu" "F.Mask" "F.Paste")
			(net "GND")
		)
		(pad "AK17" smd circle
			(at 6.002528 -0.296164)
			(size 0.3048 0.3048)
			(layers "F.Cu" "F.Mask" "F.Paste")
			(net "P0V9_CPU1_RT0_2A")
		)
		(pad "AK20" smd circle
			(at 6.002528 0.203708)
			(size 0.3048 0.3048)
			(layers "F.Cu" "F.Mask" "F.Paste")
			(net "P0V9_CPU1_RT0_2A")
		)
		(pad "AK22" smd circle
			(at 6.002528 0.703834)
			(size 0.3048 0.3048)
			(layers "F.Cu" "F.Mask" "F.Paste")
			(net "GND")
		)
		(pad "AK32" smd circle
			(at 6.002528 2.724912)
			(size 0.381 0.381)
			(layers "F.Cu" "F.Mask" "F.Paste")
			(net "GND")
		)
		(pad "AL2" smd circle
			(at 5.94995 -3.41884)
			(size 0.3048 0.3048)
			(layers "F.Cu" "F.Mask" "F.Paste")
			(net "GND")
		)
		(pad "AL34" smd circle
			(at 5.94995 3.420364)
			(size 0.3048 0.3048)
			(layers "F.Cu" "F.Mask" "F.Paste")
			(net "GND")
		)
		(pad "AM1" smd oval
			(at 5.649976 -3.938524)
			(size 0.254 0.3302)
			(layers "F.Cu" "F.Mask" "F.Paste")
			(net "GND")
		)
		(pad "AM35" smd oval
			(at 5.649976 3.940048)
			(size 0.254 0.3302)
			(layers "F.Cu" "F.Mask" "F.Paste")
			(net "GND")
		)
		(pad "AN7" smd circle
			(at 5.602478 -2.12471)
			(size 0.381 0.381)
			(layers "F.Cu" "F.Mask" "F.Paste")
			(net "P5E_CPU1_P0_TX_BUF_DP<12>")
		)
		(pad "AN26" smd circle
			(at 5.602478 1.339342)
			(size 0.381 0.381)
			(layers "F.Cu" "F.Mask" "F.Paste")
			(net "P5E_CPU1_P0_RX_DP<12>")
		)
		(pad "AP2" smd circle
			(at 5.350002 -3.41884)
			(size 0.3048 0.3048)
			(layers "F.Cu" "F.Mask" "F.Paste")
			(net "P5E_CPU1_P0_RX_BUF_DN<12>")
		)
		(pad "AP34" smd circle
			(at 5.350002 3.420364)
			(size 0.3048 0.3048)
			(layers "F.Cu" "F.Mask" "F.Paste")
			(net "P5E_CPU1_P0_TX_C_DN<12>")
		)
		(pad "AR10" smd circle
			(at 5.202682 -1.431798)
			(size 0.381 0.381)
			(layers "F.Cu" "F.Mask" "F.Paste")
			(net "P5E_CPU1_P0_TX_BUF_DN<12>")
		)
		(pad "AR29" smd circle
			(at 5.202682 2.032254)
			(size 0.381 0.381)
			(layers "F.Cu" "F.Mask" "F.Paste")
			(net "P5E_CPU1_P0_RX_DN<12>")
		)
		(pad "AT1" smd oval
			(at 5.050028 -3.938524)
			(size 0.254 0.3302)
			(layers "F.Cu" "F.Mask" "F.Paste")
			(net "P5E_CPU1_P0_RX_BUF_DP<12>")
		)
		(pad "AT35" smd oval
			(at 5.050028 3.940048)
			(size 0.254 0.3302)
			(layers "F.Cu" "F.Mask" "F.Paste")
			(net "P5E_CPU1_P0_TX_C_DP<12>")
		)
		(pad "AU4" smd circle
			(at 4.802632 -2.817368)
			(size 0.381 0.381)
			(layers "F.Cu" "F.Mask" "F.Paste")
			(net "GND")
		)
		(pad "AU13" smd circle
			(at 4.802632 -0.79629)
			(size 0.3048 0.3048)
			(layers "F.Cu" "F.Mask" "F.Paste")
			(net "GND")
		)
		(pad "AU17" smd circle
			(at 4.802632 -0.296164)
			(size 0.3048 0.3048)
			(layers "F.Cu" "F.Mask" "F.Paste")
			(net "P0V9_CPU1_RT0_2A")
		)
		(pad "AU20" smd circle
			(at 4.802632 0.203708)
			(size 0.3048 0.3048)
			(layers "F.Cu" "F.Mask" "F.Paste")
			(net "P0V9_CPU1_RT0_2A")
		)
		(pad "AU22" smd circle
			(at 4.802632 0.703834)
			(size 0.3048 0.3048)
			(layers "F.Cu" "F.Mask" "F.Paste")
			(net "GND")
		)
		(pad "AU32" smd circle
			(at 4.802632 2.724912)
			(size 0.381 0.381)
			(layers "F.Cu" "F.Mask" "F.Paste")
			(net "GND")
		)
		(pad "AV2" smd circle
			(at 4.750054 -3.41884)
			(size 0.3048 0.3048)
			(layers "F.Cu" "F.Mask" "F.Paste")
			(net "GND")
		)
		(pad "AV34" smd circle
			(at 4.750054 3.420364)
			(size 0.3048 0.3048)
			(layers "F.Cu" "F.Mask" "F.Paste")
			(net "GND")
		)
		(pad "AW1" smd oval
			(at 4.45008 -3.938524)
			(size 0.254 0.3302)
			(layers "F.Cu" "F.Mask" "F.Paste")
			(net "GND")
		)
		(pad "AW35" smd oval
			(at 4.45008 3.940048)
			(size 0.254 0.3302)
			(layers "F.Cu" "F.Mask" "F.Paste")
			(net "GND")
		)
		(pad "AY7" smd circle
			(at 4.402582 -2.12471)
			(size 0.381 0.381)
			(layers "F.Cu" "F.Mask" "F.Paste")
			(net "P5E_CPU1_P0_TX_BUF_DP<11>")
		)
		(pad "AY26" smd circle
			(at 4.402582 1.339342)
			(size 0.381 0.381)
			(layers "F.Cu" "F.Mask" "F.Paste")
			(net "P5E_CPU1_P0_RX_DP<11>")
		)
		(pad "B3" smd oval
			(at 10.885932 -2.888488 90)
			(size 0.254 0.3302)
			(layers "F.Cu" "F.Mask" "F.Paste")
			(net "JTAG_TCK_RT_CPU1_P0")
		)
		(pad "B6" smd oval
			(at 10.885932 -2.288286 90)
			(size 0.254 0.3302)
			(layers "F.Cu" "F.Mask" "F.Paste")
			(net "JTAG_TDI_RT_CPU1_P0")
		)
		(pad "B9" smd oval
			(at 10.885932 -1.688338 90)
			(size 0.254 0.3302)
			(layers "F.Cu" "F.Mask" "F.Paste")
			(net "JTAG_TDO_RT_CPU1_P0")
		)
		(pad "B12" smd oval
			(at 10.885932 -1.08839 90)
			(size 0.254 0.3302)
			(layers "F.Cu" "F.Mask" "F.Paste")
			(net "JTAG_TMS_RT_CPU1_P0")
		)
		(pad "B16" smd oval
			(at 10.885932 -0.488442 90)
			(size 0.254 0.3302)
			(layers "F.Cu" "F.Mask" "F.Paste")
			(net "Net_2217")
		)
		(pad "B19" smd oval
			(at 10.885932 0.111506 90)
			(size 0.254 0.3302)
			(layers "F.Cu" "F.Mask" "F.Paste")
			(net "GND")
		)
		(pad "B23" smd oval
			(at 10.885932 0.711708 90)
			(size 0.254 0.3302)
			(layers "F.Cu" "F.Mask" "F.Paste")
			(net "RT_CPU1_P0_ADDR2")
		)
		(pad "B25" smd oval
			(at 10.885932 1.311656 90)
			(size 0.254 0.3302)
			(layers "F.Cu" "F.Mask" "F.Paste")
			(net "RT_CPU1_P0_ADDR3")
		)
		(pad "B28" smd oval
			(at 10.885932 1.911604 90)
			(size 0.254 0.3302)
			(layers "F.Cu" "F.Mask" "F.Paste")
			(net "SMB_RT_CPU1_P0_R2_SDA")
		)
		(pad "B31" smd oval
			(at 10.885932 2.511552 90)
			(size 0.254 0.3302)
			(layers "F.Cu" "F.Mask" "F.Paste")
			(net "SMB_RT_CPU1_P0_R2_SCL")
		)
		(pad "BA2" smd circle
			(at 4.150106 -3.41884)
			(size 0.3048 0.3048)
			(layers "F.Cu" "F.Mask" "F.Paste")
			(net "P5E_CPU1_P0_RX_BUF_DN<11>")
		)
		(pad "BA34" smd circle
			(at 4.150106 3.420364)
			(size 0.3048 0.3048)
			(layers "F.Cu" "F.Mask" "F.Paste")
			(net "P5E_CPU1_P0_TX_C_DN<11>")
		)
		(pad "BB10" smd circle
			(at 4.002532 -1.431798)
			(size 0.381 0.381)
			(layers "F.Cu" "F.Mask" "F.Paste")
			(net "P5E_CPU1_P0_TX_BUF_DN<11>")
		)
		(pad "BB29" smd circle
			(at 4.002532 2.032254)
			(size 0.381 0.381)
			(layers "F.Cu" "F.Mask" "F.Paste")
			(net "P5E_CPU1_P0_RX_DN<11>")
		)
		(pad "BC1" smd oval
			(at 3.849878 -3.938524)
			(size 0.254 0.3302)
			(layers "F.Cu" "F.Mask" "F.Paste")
			(net "P5E_CPU1_P0_RX_BUF_DP<11>")
		)
		(pad "BC35" smd oval
			(at 3.849878 3.940048)
			(size 0.254 0.3302)
			(layers "F.Cu" "F.Mask" "F.Paste")
			(net "P5E_CPU1_P0_TX_C_DP<11>")
		)
		(pad "BD4" smd circle
			(at 3.602482 -2.817368)
			(size 0.381 0.381)
			(layers "F.Cu" "F.Mask" "F.Paste")
			(net "GND")
		)
		(pad "BD13" smd circle
			(at 3.602482 -0.79629)
			(size 0.3048 0.3048)
			(layers "F.Cu" "F.Mask" "F.Paste")
			(net "GND")
		)
		(pad "BD17" smd circle
			(at 3.602482 -0.296164)
			(size 0.3048 0.3048)
			(layers "F.Cu" "F.Mask" "F.Paste")
			(net "P0V9_CPU1_RT0_2A_2D")
		)
		(pad "BD20" smd circle
			(at 3.602482 0.203708)
			(size 0.3048 0.3048)
			(layers "F.Cu" "F.Mask" "F.Paste")
			(net "P0V9_CPU1_RT0_2A_2D")
		)
		(pad "BD22" smd circle
			(at 3.602482 0.703834)
			(size 0.3048 0.3048)
			(layers "F.Cu" "F.Mask" "F.Paste")
			(net "GND")
		)
		(pad "BD32" smd circle
			(at 3.602482 2.724912)
			(size 0.381 0.381)
			(layers "F.Cu" "F.Mask" "F.Paste")
			(net "GND")
		)
		(pad "BE2" smd circle
			(at 3.549904 -3.41884)
			(size 0.3048 0.3048)
			(layers "F.Cu" "F.Mask" "F.Paste")
			(net "GND")
		)
		(pad "BE34" smd circle
			(at 3.549904 3.420364)
			(size 0.3048 0.3048)
			(layers "F.Cu" "F.Mask" "F.Paste")
			(net "GND")
		)
		(pad "BF1" smd oval
			(at 3.24993 -3.938524)
			(size 0.254 0.3302)
			(layers "F.Cu" "F.Mask" "F.Paste")
			(net "GND")
		)
		(pad "BF35" smd oval
			(at 3.24993 3.940048)
			(size 0.254 0.3302)
			(layers "F.Cu" "F.Mask" "F.Paste")
			(net "GND")
		)
		(pad "BG7" smd circle
			(at 3.202686 -2.12471)
			(size 0.381 0.381)
			(layers "F.Cu" "F.Mask" "F.Paste")
			(net "P5E_CPU1_P0_TX_BUF_DP<10>")
		)
		(pad "BG26" smd circle
			(at 3.202686 1.339342)
			(size 0.381 0.381)
			(layers "F.Cu" "F.Mask" "F.Paste")
			(net "P5E_CPU1_P0_RX_DP<10>")
		)
		(pad "BH2" smd circle
			(at 2.949956 -3.41884)
			(size 0.3048 0.3048)
			(layers "F.Cu" "F.Mask" "F.Paste")
			(net "P5E_CPU1_P0_RX_BUF_DN<10>")
		)
		(pad "BH34" smd circle
			(at 2.949956 3.420364)
			(size 0.3048 0.3048)
			(layers "F.Cu" "F.Mask" "F.Paste")
			(net "P5E_CPU1_P0_TX_C_DN<10>")
		)
		(pad "BJ10" smd circle
			(at 2.802636 -1.431798)
			(size 0.381 0.381)
			(layers "F.Cu" "F.Mask" "F.Paste")
			(net "P5E_CPU1_P0_TX_BUF_DN<10>")
		)
		(pad "BJ29" smd circle
			(at 2.802636 2.032254)
			(size 0.381 0.381)
			(layers "F.Cu" "F.Mask" "F.Paste")
			(net "P5E_CPU1_P0_RX_DN<10>")
		)
		(pad "BK1" smd oval
			(at 2.649982 -3.938524)
			(size 0.254 0.3302)
			(layers "F.Cu" "F.Mask" "F.Paste")
			(net "P5E_CPU1_P0_RX_BUF_DP<10>")
		)
		(pad "BK35" smd oval
			(at 2.649982 3.940048)
			(size 0.254 0.3302)
			(layers "F.Cu" "F.Mask" "F.Paste")
			(net "P5E_CPU1_P0_TX_C_DP<10>")
		)
		(pad "BL4" smd circle
			(at 2.402586 -2.817368)
			(size 0.381 0.381)
			(layers "F.Cu" "F.Mask" "F.Paste")
			(net "GND")
		)
		(pad "BL13" smd circle
			(at 2.402586 -0.79629)
			(size 0.3048 0.3048)
			(layers "F.Cu" "F.Mask" "F.Paste")
			(net "GND")
		)
		(pad "BL17" smd circle
			(at 2.402586 -0.296164)
			(size 0.3048 0.3048)
			(layers "F.Cu" "F.Mask" "F.Paste")
			(net "P0V9_CPU1_RT_2D")
		)
		(pad "BL20" smd circle
			(at 2.402586 0.203708)
			(size 0.3048 0.3048)
			(layers "F.Cu" "F.Mask" "F.Paste")
			(net "P0V9_CPU1_RT_2D")
		)
		(pad "BL22" smd circle
			(at 2.402586 0.703834)
			(size 0.3048 0.3048)
			(layers "F.Cu" "F.Mask" "F.Paste")
			(net "GND")
		)
		(pad "BL32" smd circle
			(at 2.402586 2.724912)
			(size 0.381 0.381)
			(layers "F.Cu" "F.Mask" "F.Paste")
			(net "GND")
		)
		(pad "BM2" smd circle
			(at 2.350008 -3.41884)
			(size 0.3048 0.3048)
			(layers "F.Cu" "F.Mask" "F.Paste")
			(net "GND")
		)
		(pad "BM34" smd circle
			(at 2.350008 3.420364)
			(size 0.3048 0.3048)
			(layers "F.Cu" "F.Mask" "F.Paste")
			(net "GND")
		)
		(pad "BN1" smd oval
			(at 2.050034 -3.938524)
			(size 0.254 0.3302)
			(layers "F.Cu" "F.Mask" "F.Paste")
			(net "GND")
		)
		(pad "BN35" smd oval
			(at 2.050034 3.940048)
			(size 0.254 0.3302)
			(layers "F.Cu" "F.Mask" "F.Paste")
			(net "GND")
		)
		(pad "BP7" smd circle
			(at 2.002536 -2.12471)
			(size 0.381 0.381)
			(layers "F.Cu" "F.Mask" "F.Paste")
			(net "P5E_CPU1_P0_TX_BUF_DP<9>")
		)
		(pad "BP26" smd circle
			(at 2.002536 1.339342)
			(size 0.381 0.381)
			(layers "F.Cu" "F.Mask" "F.Paste")
			(net "P5E_CPU1_P0_RX_DP<9>")
		)
		(pad "BR2" smd circle
			(at 1.75006 -3.41884)
			(size 0.3048 0.3048)
			(layers "F.Cu" "F.Mask" "F.Paste")
			(net "P5E_CPU1_P0_RX_BUF_DN<9>")
		)
		(pad "BR34" smd circle
			(at 1.75006 3.420364)
			(size 0.3048 0.3048)
			(layers "F.Cu" "F.Mask" "F.Paste")
			(net "P5E_CPU1_P0_TX_C_DN<9>")
		)
		(pad "BT10" smd circle
			(at 1.602486 -1.431798)
			(size 0.381 0.381)
			(layers "F.Cu" "F.Mask" "F.Paste")
			(net "P5E_CPU1_P0_TX_BUF_DN<9>")
		)
		(pad "BT29" smd circle
			(at 1.602486 2.032254)
			(size 0.381 0.381)
			(layers "F.Cu" "F.Mask" "F.Paste")
			(net "P5E_CPU1_P0_RX_DN<9>")
		)
		(pad "BU1" smd oval
			(at 1.450086 -3.938524)
			(size 0.254 0.3302)
			(layers "F.Cu" "F.Mask" "F.Paste")
			(net "P5E_CPU1_P0_RX_BUF_DP<9>")
		)
		(pad "BU35" smd oval
			(at 1.450086 3.940048)
			(size 0.254 0.3302)
			(layers "F.Cu" "F.Mask" "F.Paste")
			(net "P5E_CPU1_P0_TX_C_DP<9>")
		)
		(pad "BV4" smd circle
			(at 1.20269 -2.817368)
			(size 0.381 0.381)
			(layers "F.Cu" "F.Mask" "F.Paste")
			(net "GND")
		)
		(pad "BV13" smd circle
			(at 1.20269 -0.79629)
			(size 0.3048 0.3048)
			(layers "F.Cu" "F.Mask" "F.Paste")
			(net "GND")
		)
		(pad "BV17" smd circle
			(at 1.20269 -0.296164)
			(size 0.3048 0.3048)
			(layers "F.Cu" "F.Mask" "F.Paste")
			(net "P1V8_CPU1_RT0_1A_1D")
		)
		(pad "BV20" smd circle
			(at 1.20269 0.203708)
			(size 0.3048 0.3048)
			(layers "F.Cu" "F.Mask" "F.Paste")
			(net "P1V8_CPU1_RT0_1A")
		)
		(pad "BV22" smd circle
			(at 1.20269 0.703834)
			(size 0.3048 0.3048)
			(layers "F.Cu" "F.Mask" "F.Paste")
			(net "GND")
		)
	)
)
